# BASEBOARD_FAB2 (Tioga Pass) — schematic netlist excerpt (pin names and nets, part order shuffled) for the footprints in the layout excerpt that follows; sources: Cadence DE-HDL packaged netlist, KiCad conversion of Wiwynn_Tioga_Pass_MB.brd

L7A3  IND-120NH-30-GP  pkg DISCRET-GB2  page 219 : S = VR_PVDDQ_DEF_PH2_SW ; F = PVDDQ_DEF
C1E13  CAP  1.0UF 16V 10% X6S  pkg 0402  page 207 : A = VR_FET_SW_P12V_STBY_PVCCIN_CPU1 ; B = GND

(kicad_pcb
	(version 20260206)
	(generator "pcbnew")
	(generator_version "10.0")
	(general
		(thickness 1.6)
		(legacy_teardrops no)
	)
	(paper "A4")
	(title_block
		(title "Wiwynn_Tioga_Pass_MB.brd")
		(comment 1 "Tioga Pass / footprints 1079-1080 of 4770")
	)
	(layers
		(0 "F.Cu" signal "TOP")
		(4 "In1.Cu" signal "L2GND")
		(6 "In2.Cu" signal "L3")
		(8 "In3.Cu" signal "L4GND")
		(10 "In4.Cu" signal "L5")
		(12 "In5.Cu" signal "L6GND")
		(14 "In6.Cu" signal "L7VCC")
		(16 "In7.Cu" signal "L8VCC")
		(18 "In8.Cu" signal "L9GND")
		(20 "In9.Cu" signal "L10")
		(22 "In10.Cu" signal "L11GND")
		(24 "In11.Cu" signal "L12")
		(26 "In12.Cu" signal "L13GND")
		(2 "B.Cu" signal "BOTTOM")
		(9 "F.Adhes" user "F.Adhesive")
		(11 "B.Adhes" user "B.Adhesive")
		(13 "F.Paste" user "Package Geometry/Pastemask Top")
		(15 "B.Paste" user "Package Geometry/Pastemask Bottom")
		(5 "F.SilkS" user "Ref Des/Silkscreen Top")
		(7 "B.SilkS" user "Ref Des/Silkscreen Bottom")
		(1 "F.Mask" user "Board Geometry/Soldermask Top")
		(3 "B.Mask" user "Board Geometry/Soldermask Bottom")
		(17 "Dwgs.User" user "User.Drawings")
		(19 "Cmts.User" user "User.Comments")
		(21 "Eco1.User" user "User.Eco1")
		(23 "Eco2.User" user "User.Eco2")
		(25 "Edge.Cuts" user "Board Geometry/Outline")
		(27 "Margin" user)
		(31 "F.CrtYd" user "Package Geometry/Place Bound Top")
		(29 "B.CrtYd" user "Package Geometry/Place Bound Bottom")
		(35 "F.Fab" user "Ref Des/Assembly Top")
		(33 "B.Fab" user "Ref Des/Assembly Bottom")
	)
	(footprint ""
		(layer "F.Cu")
		(at 29.6164 -59.617102 -90)
		(property "Reference" "C1E13"
			(at 0 0 270)
			(layer "F.SilkS")
			(hide yes)
			(effects
				(font
					(size 1.27 1.27)
				)
			)
		)
		(property "Value" ""
			(at 0 0 270)
			(layer "F.Fab")
			(effects
				(font
					(size 1.27 1.27)
				)
			)
		)
		(duplicate_pad_numbers_are_jumpers no)
		(fp_rect
			(start 0.3048 -0.1016)
			(end -0.3048 0.9906)
			(stroke
				(width 0)
				(type default)
			)
			(fill no)
			(layer "F.CrtYd")
		)
		(fp_line
			(start -0.3048 0.9906)
			(end 0.3048 0.9906)
			(stroke
				(width 0.1)
				(type default)
			)
			(layer "F.Fab")
		)
		(fp_line
			(start 0.3048 0.9906)
			(end 0.3048 -0.1016)
			(stroke
				(width 0.1)
				(type default)
			)
			(layer "F.Fab")
		)
		(fp_line
			(start -0.3048 -0.1016)
			(end -0.3048 0.9906)
			(stroke
				(width 0.1)
				(type default)
			)
			(layer "F.Fab")
		)
		(fp_line
			(start 0.3048 -0.1016)
			(end -0.3048 -0.1016)
			(stroke
				(width 0.1)
				(type default)
			)
			(layer "F.Fab")
		)
		(pad "1" smd rect
			(at 0 0 270)
			(size 0.508 0.508)
			(layers "F.Cu" "F.Mask" "F.Paste")
			(net "VR_FET_SW_P12V_STBY_PVCCIN_CPU1")
		)
		(pad "2" smd rect
			(at 0 0.889 270)
			(size 0.508 0.508)
			(layers "F.Cu" "F.Mask" "F.Paste")
			(net "GND")
		)
		(zone
			(layer "F.Cu")
			(hatch none 0.5)
			(connect_pads
				(clearance 0)
			)
			(min_thickness 0.25)
			(keepout
				(tracks not_allowed)
				(vias allowed)
				(pads allowed)
				(copperpour not_allowed)
				(footprints allowed)
			)
			(placement
				(enabled no)
				(sheetname "")
			)
			(fill
				(thermal_gap 0.5)
				(thermal_bridge_width 0.5)
				(island_removal_mode 0)
			)
			(polygon
				(pts
					(xy 29.3624 -59.363102) (xy 29.3624 -59.871102) (xy 28.9814 -59.871102) (xy 28.9814 -59.363102)
				)
			)
		)
		(zone
			(layer "F.Cu")
			(hatch none 0.5)
			(connect_pads
				(clearance 0)
			)
			(min_thickness 0.25)
			(keepout
				(tracks allowed)
				(vias not_allowed)
				(pads allowed)
				(copperpour not_allowed)
				(footprints allowed)
			)
			(placement
				(enabled no)
				(sheetname "")
			)
			(fill
				(thermal_gap 0.5)
				(thermal_bridge_width 0.5)
				(island_removal_mode 0)
			)
			(polygon
				(pts
					(xy 29.3624 -59.363102) (xy 29.3624 -59.871102) (xy 28.9814 -59.871102) (xy 28.9814 -59.363102)
				)
			)
		)
	)
	(footprint ""
		(layer "F.Cu")
		(at 341.3506 -147.461224 180)
		(property "Reference" "L7A3"
			(at 3.378708 -4.251706 180)
			(unlocked yes)
			(layer "F.SilkS")
			(effects
				(font
					(size 0.4064 0.254)
					(thickness 0.1524)
				)
			)
		)
		(property "Value" ""
			(at 0 0 180)
			(layer "F.Fab")
			(effects
				(font
					(size 1.27 1.27)
				)
			)
		)
		(duplicate_pad_numbers_are_jumpers no)
		(fp_line
			(start 8.3693 3.199892)
			(end -1.1303 3.199892)
			(stroke
				(width 0.1524)
				(type default)
			)
			(layer "F.SilkS")
		)
		(fp_line
			(start 8.3693 1.6637)
			(end 8.3693 3.199892)
			(stroke
				(width 0.1524)
				(type default)
			)
			(layer "F.SilkS")
		)
		(fp_line
			(start 8.3693 -3.199892)
			(end 8.3693 -1.6637)
			(stroke
				(width 0.1524)
				(type default)
			)
			(layer "F.SilkS")
		)
		(fp_line
			(start -1.1303 3.199892)
			(end -1.1303 1.6637)
			(stroke
				(width 0.1524)
				(type default)
			)
			(layer "F.SilkS")
		)
		(fp_line
			(start -1.1303 -1.6637)
			(end -1.1303 -3.199892)
			(stroke
				(width 0.1524)
				(type default)
			)
			(layer "F.SilkS")
		)
		(fp_line
			(start -1.1303 -3.199892)
			(end 8.3693 -3.199892)
			(stroke
				(width 0.1524)
				(type default)
			)
			(layer "F.SilkS")
		)
		(fp_rect
			(start -1.1303 3.199892)
			(end 8.3693 -3.199892)
			(stroke
				(width 0)
				(type default)
			)
			(fill no)
			(layer "F.CrtYd")
		)
		(fp_line
			(start 8.3693 3.199892)
			(end -1.1303 3.199892)
			(stroke
				(width 0.1)
				(type default)
			)
			(layer "F.Fab")
		)
		(fp_line
			(start 8.3693 -3.199892)
			(end 8.3693 3.199892)
			(stroke
				(width 0.1)
				(type default)
			)
			(layer "F.Fab")
		)
		(fp_line
			(start -1.1303 3.199892)
			(end -1.1303 -3.199892)
			(stroke
				(width 0.1)
				(type default)
			)
			(layer "F.Fab")
		)
		(fp_line
			(start -1.1303 -3.199892)
			(end 8.3693 -3.199892)
			(stroke
				(width 0.1)
				(type default)
			)
			(layer "F.Fab")
		)
		(pad "1" smd rect
			(at 0 0 180)
			(size 3.683 2.667)
			(layers "F.Cu" "F.Mask" "F.Paste")
			(net "VR_PVDDQ_DEF_PH2_SW")
		)
		(pad "2" smd rect
			(at 7.239 0 180)
			(size 3.683 2.667)
			(layers "F.Cu" "F.Mask" "F.Paste")
			(net "PVDDQ_DEF")
		)
	)
)
